#ISCELL
  mstr_misc dns *
  *
#ISCELL
  pure_quanta quanta_title_block_c *
  *
#ISCELL
  pure_quanta_power cad_note *
  *
#ISCELL
  standard offpage *
  page324_i1
#ISCELL
  pure_quanta_power gnd *
  page324_i10
#CELL
  pure_quanta q_res *
  page324_i11
#CELL
  pure_quanta mosfet_nch_dual *
  page324_i12
#ISCELL
  pure_quanta_power gnd *
  page324_i13
#ISCELL
  pure_quanta_power gnd *
  page324_i14
#ISCELL
  pure_quanta_power gnd *
  page324_i15
#CELL
  pure_quanta q_res *
  page324_i16
#CELL
  pure_quanta q_res *
  page324_i17
#CELL
  pure_quanta q_res *
  page324_i18
#ISCELL
  pure_quanta_power gnd *
  page324_i19
#CELL
  pure_quanta q_res *
  page324_i2
#CELL
  pure_quanta q_cap *
  page324_i20
#CELL
  pure_quanta q_res *
  page324_i21
#ISCELL
  pure_quanta_power universal_power *
  page324_i22
#ISCELL
  standard offpage *
  page324_i23
#CELL
  pure_quanta q_res *
  page324_i24
#CELL
  pure_quanta q_res *
  page324_i25
#ISCELL
  pure_quanta_power universal_power *
  page324_i26
#CELL
  pure_quanta mosfet_nch_dual *
  page324_i27
#ISCELL
  pure_quanta_power gnd *
  page324_i28
#CELL
  pure_quanta q_res *
  page324_i29
#ISCELL
  pure_quanta_power gnd *
  page324_i3
#ISCELL
  pure_quanta_power gnd *
  page324_i30
#CELL
  pure_quanta q_res *
  page324_i31
#CELL
  pure_quanta q_res *
  page324_i32
#CELL
  pure_quanta diode_tvs *
  page324_i33
#ISCELL
  pure_quanta_power gnd *
  page324_i34
#ISCELL
  pure_quanta_power universal_power *
  page324_i35
#CELL
  pure_quanta q_cap *
  page324_i36
#CELL
  pure_quanta q_res *
  page324_i37
#ISCELL
  pure_quanta_power gnd *
  page324_i38
#CELL
  pure_quanta q_res *
  page324_i39
#CELL
  pure_quanta q_res *
  page324_i4
#ISCELL
  pure_quanta_power gnd *
  page324_i40
#CELL
  pure_quanta q_cap *
  page324_i41
#CELL
  pure_quanta q_cap *
  page324_i42
#CELL
  pure_quanta q_res *
  page324_i43
#ISCELL
  pure_quanta_power gnd *
  page324_i44
#CELL
  pure_quanta q_res *
  page324_i45
#CELL
  pure_quanta q_cap *
  page324_i46
#CELL
  pure_quanta q_res *
  page324_i47
#CELL
  pure_quanta q_res *
  page324_i48
#CELL
  pure_quanta q_cap *
  page324_i49
#ISCELL
  pure_quanta_power gnd *
  page324_i5
#CELL
  pure_quanta schottky_ac *
  page324_i50
#ISCELL
  pure_quanta_power gnd *
  page324_i51
#CELL
  pure_quanta q_res *
  page324_i52
#ISCELL
  pure_quanta_power vccaux15 *
  page324_i53
#CELL
  pure_quanta q_res *
  page324_i54
#ISCELL
  standard offpage *
  page324_i55
#ISCELL
  pure_quanta_power gnd *
  page324_i56
#CELL
  pure_quanta q_cap *
  page324_i57
#CELL
  pure_quanta q_cap *
  page324_i58
#ISCELL
  pure_quanta_power universal_power *
  page324_i59
#CELL
  pure_quanta mosfet_nch_dual *
  page324_i6
#ISCELL
  pure_quanta_power gnd *
  page324_i60
#CELL
  pure_quanta q_cap *
  page324_i61
#ISCELL
  pure_quanta_power gnd *
  page324_i62
#CELL
  pure_quanta q_res *
  page324_i63
#CELL
  pure_quanta q_cap *
  page324_i64
#CELL
  pure_quanta q_res *
  page324_i65
#CELL
  pure_quanta max15090bewit *
  page324_i66
#ISCELL
  pure_quanta_power gnd *
  page324_i67
#CELL
  pure_quanta q_res *
  page324_i68
#CELL
  pure_quanta q_cap *
  page324_i69
#CELL
  pure_quanta mosfet_nch_dual *
  page324_i7
#CELL
  pure_quanta q_res *
  page324_i70
#CELL
  pure_quanta q_res *
  page324_i71
#CELL
  pure_quanta q_cap *
  page324_i72
#CELL
  pure_quanta q_res *
  page324_i73
#CELL
  pure_quanta schottky_ac *
  page324_i74
#ISCELL
  pure_quanta_power gnd *
  page324_i75
#CELL
  pure_quanta q_res *
  page324_i76
#ISCELL
  pure_quanta_power vccaux15 *
  page324_i77
#CELL
  pure_quanta q_cap *
  page324_i78
#CELL
  pure_quanta q_cap *
  page324_i79
#CELL
  pure_quanta q_res *
  page324_i8
#CELL
  pure_quanta q_cap *
  page324_i80
#ISCELL
  pure_quanta_power universal_power *
  page324_i81
#ISCELL
  standard offpage *
  page324_i82
#ISCELL
  standard offpage *
  page324_i83
#ISCELL
  standard offpage *
  page324_i84
#ISCELL
  pure_quanta_power gnd *
  page324_i85
#CELL
  pure_quanta q_res *
  page324_i86
#CELL
  pure_quanta q_res *
  page324_i87
#CELL
  pure_quanta max15090bewit *
  page324_i88
#ISCELL
  pure_quanta_power universal_power *
  page324_i9
